# S9S_MB_2U (Grand Teton) — schematic netlist excerpt (pin names and nets, part order shuffled) for the footprints in the layout excerpt that follows; sources: Cadence DE-HDL packaged netlist, KiCad conversion of 03242023_DA0F0TMBIJ0_F0T_Motherboard_J_brd_V01_OCP.brd

R4640  Q_RES  243 1% CHIP  pkg 1206LF  page 260 : A = P5V ; B = VR_P5V_EN_D
R3080  Q_RES  130 1% CHIP  pkg 0402LF  page 256 : A = LED_RST_PLD_CPU0_DRAM_CD_N ; B = P3V3_AUX
R756  Q_RES  10 1% CHIP  pkg 0402LF  page 132 : A = JTAG_DBP_PRDY_N ; B = H_DBP_PRDY_N_PCH

(kicad_pcb
	(version 20260206)
	(generator "pcbnew")
	(generator_version "10.0")
	(general
		(thickness 1.6)
		(legacy_teardrops no)
	)
	(paper "A4")
	(title_block
		(title "03242023_DA0F0TMBIJ0_F0T_Motherboard_J_brd_V01_OCP.brd")
		(comment 1 "Grand Teton / footprints 553-555 of 6105")
	)
	(layers
		(0 "F.Cu" signal "TOP")
		(4 "In1.Cu" signal "GND")
		(6 "In2.Cu" signal "IN1")
		(8 "In3.Cu" signal "GND1")
		(10 "In4.Cu" signal "IN2")
		(12 "In5.Cu" signal "GND2")
		(14 "In6.Cu" signal "IN3")
		(16 "In7.Cu" signal "GND3")
		(18 "In8.Cu" signal "VCC")
		(20 "In9.Cu" signal "VCC1")
		(22 "In10.Cu" signal "GND4")
		(24 "In11.Cu" signal "IN4")
		(26 "In12.Cu" signal "GND5")
		(28 "In13.Cu" signal "IN5")
		(30 "In14.Cu" signal "GND6")
		(32 "In15.Cu" signal "IN6")
		(34 "In16.Cu" signal "GND7")
		(2 "B.Cu" signal "BOTTOM")
		(9 "F.Adhes" user "F.Adhesive")
		(11 "B.Adhes" user "B.Adhesive")
		(13 "F.Paste" user "Package Geometry/Pastemask Top")
		(15 "B.Paste" user "Package Geometry/Pastemask Bottom")
		(5 "F.SilkS" user "Ref Des/Silkscreen Top")
		(7 "B.SilkS" user "Ref Des/Silkscreen Bottom")
		(1 "F.Mask" user "Board Geometry/Soldermask Top")
		(3 "B.Mask" user "Board Geometry/Soldermask Bottom")
		(17 "Dwgs.User" user "User.Drawings")
		(19 "Cmts.User" user "User.Comments")
		(21 "Eco1.User" user "User.Eco1")
		(23 "Eco2.User" user "User.Eco2")
		(25 "Edge.Cuts" user "Board Geometry/Outline")
		(27 "Margin" user)
		(31 "F.CrtYd" user "Package Geometry/Place Bound Top")
		(29 "B.CrtYd" user "Package Geometry/Place Bound Bottom")
		(35 "F.Fab" user "Ref Des/Assembly Top")
		(33 "B.Fab" user "Ref Des/Assembly Bottom")
	)
	(footprint ""
		(layer "F.Cu")
		(at 77.381354 -65.082674 -90)
		(property "Reference" "R3080"
			(at 0 0 270)
			(layer "F.SilkS")
			(hide yes)
			(effects
				(font
					(size 1.27 1.27)
				)
			)
		)
		(property "Value" ""
			(at 0 0 270)
			(layer "F.Fab")
			(effects
				(font
					(size 1.27 1.27)
				)
			)
		)
		(duplicate_pad_numbers_are_jumpers no)
		(fp_line
			(start -0.7874 0.4064)
			(end -0.7874 -0.4064)
			(stroke
				(width 0.1524)
				(type default)
			)
			(layer "F.SilkS")
		)
		(fp_line
			(start 0.7874 0.4064)
			(end -0.7874 0.4064)
			(stroke
				(width 0.1524)
				(type default)
			)
			(layer "F.SilkS")
		)
		(fp_line
			(start -0.7874 -0.4064)
			(end 0.7874 -0.4064)
			(stroke
				(width 0.1524)
				(type default)
			)
			(layer "F.SilkS")
		)
		(fp_line
			(start 0.7874 -0.4064)
			(end 0.7874 0.4064)
			(stroke
				(width 0.1524)
				(type default)
			)
			(layer "F.SilkS")
		)
		(fp_line
			(start -0.67945 0.3048)
			(end -0.67945 -0.305054)
			(stroke
				(width 0.1)
				(type default)
			)
			(layer "F.Fab")
		)
		(fp_line
			(start -0.12065 0.3048)
			(end -0.67945 0.3048)
			(stroke
				(width 0.1)
				(type default)
			)
			(layer "F.Fab")
		)
		(fp_line
			(start 0.120396 0.3048)
			(end 0.120396 0.2794)
			(stroke
				(width 0.1)
				(type default)
			)
			(layer "F.Fab")
		)
		(fp_line
			(start 0.67945 0.3048)
			(end 0.120396 0.3048)
			(stroke
				(width 0.1)
				(type default)
			)
			(layer "F.Fab")
		)
		(fp_line
			(start -0.12065 0.2794)
			(end -0.12065 0.3048)
			(stroke
				(width 0.1)
				(type default)
			)
			(layer "F.Fab")
		)
		(fp_line
			(start 0.120396 0.2794)
			(end -0.12065 0.2794)
			(stroke
				(width 0.1)
				(type default)
			)
			(layer "F.Fab")
		)
		(fp_line
			(start -0.12065 -0.2794)
			(end 0.12065 -0.2794)
			(stroke
				(width 0.1)
				(type default)
			)
			(layer "F.Fab")
		)
		(fp_line
			(start 0.12065 -0.2794)
			(end 0.12065 -0.3048)
			(stroke
				(width 0.1)
				(type default)
			)
			(layer "F.Fab")
		)
		(fp_line
			(start 0.12065 -0.3048)
			(end 0.67945 -0.3048)
			(stroke
				(width 0.1)
				(type default)
			)
			(layer "F.Fab")
		)
		(fp_line
			(start 0.67945 -0.3048)
			(end 0.67945 0.3048)
			(stroke
				(width 0.1)
				(type default)
			)
			(layer "F.Fab")
		)
		(fp_line
			(start -0.67945 -0.305054)
			(end -0.12065 -0.305054)
			(stroke
				(width 0.1)
				(type default)
			)
			(layer "F.Fab")
		)
		(fp_line
			(start -0.12065 -0.305054)
			(end -0.12065 -0.2794)
			(stroke
				(width 0.1)
				(type default)
			)
			(layer "F.Fab")
		)
		(pad "1" smd circle
			(at -0.40005 0 270)
			(size 0 0)
			(layers "F.Cu" "F.Mask" "F.Paste")
			(net "LED_RST_PLD_CPU0_DRAM_CD_N")
		)
		(pad "2" smd circle
			(at 0.40005 0 270)
			(size 0 0)
			(layers "F.Cu" "F.Mask" "F.Paste")
			(net "P3V3_AUX")
		)
	)
	(footprint ""
		(layer "F.Cu")
		(at 159.258 -126.365 -90)
		(property "Reference" "R4640"
			(at 0 0 270)
			(layer "F.SilkS")
			(hide yes)
			(effects
				(font
					(size 1.27 1.27)
				)
			)
		)
		(property "Value" ""
			(at 0 0 270)
			(layer "F.Fab")
			(effects
				(font
					(size 1.27 1.27)
				)
			)
		)
		(duplicate_pad_numbers_are_jumpers no)
		(fp_line
			(start -2.234946 0.9271)
			(end -2.234946 -0.9271)
			(stroke
				(width 0.1524)
				(type default)
			)
			(layer "F.SilkS")
		)
		(fp_line
			(start 2.234946 0.9271)
			(end -2.234946 0.9271)
			(stroke
				(width 0.1524)
				(type default)
			)
			(layer "F.SilkS")
		)
		(fp_line
			(start -2.234946 -0.9271)
			(end 2.234946 -0.9271)
			(stroke
				(width 0.1524)
				(type default)
			)
			(layer "F.SilkS")
		)
		(fp_line
			(start 2.234946 -0.9271)
			(end 2.234946 0.9271)
			(stroke
				(width 0.1524)
				(type default)
			)
			(layer "F.SilkS")
		)
		(fp_line
			(start -1.575054 0.824992)
			(end 1.575054 0.824992)
			(stroke
				(width 0.1)
				(type default)
			)
			(layer "F.Fab")
		)
		(fp_line
			(start 1.575054 0.824992)
			(end 1.575054 -0.824992)
			(stroke
				(width 0.1)
				(type default)
			)
			(layer "F.Fab")
		)
		(fp_line
			(start -1.575054 -0.824992)
			(end -1.575054 0.824992)
			(stroke
				(width 0.1)
				(type default)
			)
			(layer "F.Fab")
		)
		(fp_line
			(start 1.575054 -0.824992)
			(end -1.575054 -0.824992)
			(stroke
				(width 0.1)
				(type default)
			)
			(layer "F.Fab")
		)
		(pad "1" smd rect
			(at -1.599946 0 270)
			(size 1.016 1.6002)
			(layers "F.Cu" "F.Mask" "F.Paste")
			(net "P5V")
		)
		(pad "2" smd rect
			(at 1.599946 0 270)
			(size 1.016 1.6002)
			(layers "F.Cu" "F.Mask" "F.Paste")
			(net "VR_P5V_EN_D")
		)
	)
	(footprint ""
		(layer "F.Cu")
		(at 374.16359 -64.866012)
		(property "Reference" "R756"
			(at 0 0 0)
			(layer "F.SilkS")
			(hide yes)
			(effects
				(font
					(size 1.27 1.27)
				)
			)
		)
		(property "Value" ""
			(at 0 0 0)
			(layer "F.Fab")
			(effects
				(font
					(size 1.27 1.27)
				)
			)
		)
		(duplicate_pad_numbers_are_jumpers no)
		(fp_line
			(start -0.7874 -0.4064)
			(end 0.7874 -0.4064)
			(stroke
				(width 0.1524)
				(type default)
			)
			(layer "F.SilkS")
		)
		(fp_line
			(start -0.7874 0.4064)
			(end -0.7874 -0.4064)
			(stroke
				(width 0.1524)
				(type default)
			)
			(layer "F.SilkS")
		)
		(fp_line
			(start 0.7874 -0.4064)
			(end 0.7874 0.4064)
			(stroke
				(width 0.1524)
				(type default)
			)
			(layer "F.SilkS")
		)
		(fp_line
			(start 0.7874 0.4064)
			(end -0.7874 0.4064)
			(stroke
				(width 0.1524)
				(type default)
			)
			(layer "F.SilkS")
		)
		(fp_line
			(start -0.67945 -0.305054)
			(end -0.12065 -0.305054)
			(stroke
				(width 0.1)
				(type default)
			)
			(layer "F.Fab")
		)
		(fp_line
			(start -0.67945 0.3048)
			(end -0.67945 -0.305054)
			(stroke
				(width 0.1)
				(type default)
			)
			(layer "F.Fab")
		)
		(fp_line
			(start -0.12065 -0.305054)
			(end -0.12065 -0.2794)
			(stroke
				(width 0.1)
				(type default)
			)
			(layer "F.Fab")
		)
		(fp_line
			(start -0.12065 -0.2794)
			(end 0.12065 -0.2794)
			(stroke
				(width 0.1)
				(type default)
			)
			(layer "F.Fab")
		)
		(fp_line
			(start -0.12065 0.2794)
			(end -0.12065 0.3048)
			(stroke
				(width 0.1)
				(type default)
			)
			(layer "F.Fab")
		)
		(fp_line
			(start -0.12065 0.3048)
			(end -0.67945 0.3048)
			(stroke
				(width 0.1)
				(type default)
			)
			(layer "F.Fab")
		)
		(fp_line
			(start 0.120396 0.2794)
			(end -0.12065 0.2794)
			(stroke
				(width 0.1)
				(type default)
			)
			(layer "F.Fab")
		)
		(fp_line
			(start 0.120396 0.3048)
			(end 0.120396 0.2794)
			(stroke
				(width 0.1)
				(type default)
			)
			(layer "F.Fab")
		)
		(fp_line
			(start 0.12065 -0.3048)
			(end 0.67945 -0.3048)
			(stroke
				(width 0.1)
				(type default)
			)
			(layer "F.Fab")
		)
		(fp_line
			(start 0.12065 -0.2794)
			(end 0.12065 -0.3048)
			(stroke
				(width 0.1)
				(type default)
			)
			(layer "F.Fab")
		)
		(fp_line
			(start 0.67945 -0.3048)
			(end 0.67945 0.3048)
			(stroke
				(width 0.1)
				(type default)
			)
			(layer "F.Fab")
		)
		(fp_line
			(start 0.67945 0.3048)
			(end 0.120396 0.3048)
			(stroke
				(width 0.1)
				(type default)
			)
			(layer "F.Fab")
		)
		(pad "1" smd circle
			(at -0.40005 0)
			(size 0 0)
			(layers "F.Cu" "F.Mask" "F.Paste")
			(net "JTAG_DBP_PRDY_N")
		)
		(pad "2" smd circle
			(at 0.40005 0)
			(size 0 0)
			(layers "F.Cu" "F.Mask" "F.Paste")
			(net "H_DBP_PRDY_N_PCH")
		)
	)
)
